(kicad_pcb
	(version 20221018)
	(generator pcbnew)
	(general
    (thickness 1.586)
  )
	(paper "A4")
	(title_block
    (date "2024-03-26")
    (rev "1.1.3")
		(comment 9 "footprints 1-2 of 146")
	)
	(layers
    (0 "F.Cu" signal)
    (1 "In1.Cu" power)
    (2 "In2.Cu" power)
    (31 "B.Cu" signal)
    (32 "B.Adhes" user "B.Adhesive")
    (33 "F.Adhes" user "F.Adhesive")
    (34 "B.Paste" user)
    (35 "F.Paste" user)
    (36 "B.SilkS" user "B.Silkscreen")
    (37 "F.SilkS" user "F.Silkscreen")
    (38 "B.Mask" user)
    (39 "F.Mask" user)
    (40 "Dwgs.User" user "User.Drawings")
    (41 "Cmts.User" user "User.Comments")
    (42 "Eco1.User" user "User.Eco1")
    (43 "Eco2.User" user "User.Eco2")
    (44 "Edge.Cuts" user)
    (45 "Margin" user)
    (46 "B.CrtYd" user "B.Courtyard")
    (47 "F.CrtYd" user "F.Courtyard")
    (48 "B.Fab" user)
    (49 "F.Fab" user)
  )
	(footprint "scalenode-cm4-baseboard-footprints:Spacer_Drill3.7mm_H3mm_9774030151R" (layer "F.Cu")
    (at 193.488 93.2)
    (property "Author" "Antmicro")
    (property "License" "Apache-2.0")
    (property "MPN" "9774030151R")
    (property "Manufacturer" "Würth Elektronik")
    (property "Sheetfile" "compute-module.kicad_sch")
    (property "Sheetname" "Compute module")
    (property "ki_description" "Spacer, SMT,  Steel, Swage Round, 5.1mmx3mm, M3 Thread, WA-SMSI Series")
    (property "ki_keywords" "SPACER")
    (attr through_hole)
    (fp_text reference "SP5" (at -0.052 -3.65) (layer "F.SilkS")
        (effects (font (size 0.7 0.7) (thickness 0.15)) (justify left bottom))
    )
    (fp_text value "Spacer_Drill3.7mm_H3mm_9774030151R" (at 1.387 2.4) (layer "F.Fab")
        (effects (font (size 0.7 0.7) (thickness 0.15)) (justify left bottom))
    )
    (fp_text user "License: Apache-2.0" (at -2.601 8.8) (layer "F.Fab") hide
        (effects (font (size 0.7 0.7) (thickness 0.15)) (justify left bottom))
    )
    (fp_text user "${REFERENCE}" (at -2.601 6.398) (layer "F.Fab") hide
        (effects (font (size 0.7 0.7) (thickness 0.15)) (justify left bottom))
    )
    (fp_text user "Author: Antmicro" (at -2.601 7.599) (layer "F.Fab") hide
        (effects (font (size 0.7 0.7) (thickness 0.15)) (justify left bottom))
    )
    (fp_circle (center 0 0) (end 3.1 0)
      (stroke (width 0.12) (type solid)) (fill none) (layer "F.SilkS"))
    (fp_circle (center 0 0) (end 3.15 0)
      (stroke (width 0.05) (type solid)) (fill none) (layer "F.CrtYd"))
    (pad "" smd custom (at -1.709 -1.709) (size 0.62 0.62) (layers "F.Paste")
      (options (clearance outline) (anchor circle))
      (primitives
        (gr_arc (start -0.250195 1.279127) (mid 0.285453 0.294389) (end 1.266786 -0.24747) (width 0.2))
        (gr_arc (start -0.34334 1.279127) (mid 0.221018 0.229971) (end 1.266737 -0.340731) (width 0.2))
        (gr_arc (start -0.436309 1.279127) (mid 0.15516 0.166988) (end 1.262733 -0.432988) (width 0.2))
        (gr_arc (start -0.529126 1.279127) (mid 0.093127 0.100154) (end 1.269368 -0.527248) (width 0.2))
        (gr_arc (start -0.621807 1.279127) (mid 0.0309 0.033527) (end 1.275473 -0.621136) (width 0.2))
        (gr_arc (start -0.71437 1.279127) (mid -0.037758 -0.026651) (end 1.263665 -0.711602) (width 0.2))
        (gr_arc (start -0.806826 1.279127) (mid -0.105832 -0.087398) (end 1.253445 -0.802344) (width 0.2))
        (gr_arc (start -0.899187 1.279127) (mid -0.163611 -0.158516) (end 1.272017 -0.898016) (width 0.2))
        (gr_arc (start -0.991463 1.279127) (mid -0.228522 -0.222449) (end 1.270645 -0.990112) (width 0.2))
        (gr_arc (start -1.083663 1.279127) (mid -0.294507 -0.285313) (end 1.266278 -1.081674) (width 0.2))
        (gr_line (start 1.279127 -0.250195) (end 1.279127 -1.083663) (width 0.2))
        (gr_line (start -0.250195 1.279127) (end -1.083663 1.279127) (width 0.2))
      ))
    (pad "" smd custom (at -1.709 1.7 90) (size 0.62 0.62) (layers "F.Paste")
      (options (clearance outline) (anchor circle))
      (primitives
        (gr_arc (start -0.250195 1.279127) (mid 0.285453 0.294389) (end 1.266786 -0.24747) (width 0.2))
        (gr_arc (start -0.34334 1.279127) (mid 0.221018 0.229971) (end 1.266737 -0.340731) (width 0.2))
        (gr_arc (start -0.436309 1.279127) (mid 0.15516 0.166988) (end 1.262733 -0.432988) (width 0.2))
        (gr_arc (start -0.529126 1.279127) (mid 0.093127 0.100154) (end 1.269368 -0.527248) (width 0.2))
        (gr_arc (start -0.621807 1.279127) (mid 0.0309 0.033527) (end 1.275473 -0.621136) (width 0.2))
        (gr_arc (start -0.71437 1.279127) (mid -0.037758 -0.026651) (end 1.263665 -0.711602) (width 0.2))
        (gr_arc (start -0.806826 1.279127) (mid -0.105832 -0.087398) (end 1.253445 -0.802344) (width 0.2))
        (gr_arc (start -0.899187 1.279127) (mid -0.163611 -0.158516) (end 1.272017 -0.898016) (width 0.2))
        (gr_arc (start -0.991463 1.279127) (mid -0.228522 -0.222449) (end 1.270645 -0.990112) (width 0.2))
        (gr_arc (start -1.083663 1.279127) (mid -0.294507 -0.285313) (end 1.266278 -1.081674) (width 0.2))
        (gr_line (start 1.279127 -0.250195) (end 1.279127 -1.083663) (width 0.2))
        (gr_line (start -0.250195 1.279127) (end -1.083663 1.279127) (width 0.2))
      ))
    (pad "" smd custom (at 1.7 -1.709 270) (size 0.62 0.62) (layers "F.Paste")
      (options (clearance outline) (anchor circle))
      (primitives
        (gr_arc (start -0.250195 1.279127) (mid 0.285453 0.294389) (end 1.266786 -0.24747) (width 0.2))
        (gr_arc (start -0.34334 1.279127) (mid 0.221018 0.229971) (end 1.266737 -0.340731) (width 0.2))
        (gr_arc (start -0.436309 1.279127) (mid 0.15516 0.166988) (end 1.262733 -0.432988) (width 0.2))
        (gr_arc (start -0.529126 1.279127) (mid 0.093127 0.100154) (end 1.269368 -0.527248) (width 0.2))
        (gr_arc (start -0.621807 1.279127) (mid 0.0309 0.033527) (end 1.275473 -0.621136) (width 0.2))
        (gr_arc (start -0.71437 1.279127) (mid -0.037758 -0.026651) (end 1.263665 -0.711602) (width 0.2))
        (gr_arc (start -0.806826 1.279127) (mid -0.105832 -0.087398) (end 1.253445 -0.802344) (width 0.2))
        (gr_arc (start -0.899187 1.279127) (mid -0.163611 -0.158516) (end 1.272017 -0.898016) (width 0.2))
        (gr_arc (start -0.991463 1.279127) (mid -0.228522 -0.222449) (end 1.270645 -0.990112) (width 0.2))
        (gr_arc (start -1.083663 1.279127) (mid -0.294507 -0.285313) (end 1.266278 -1.081674) (width 0.2))
        (gr_line (start 1.279127 -0.250195) (end 1.279127 -1.083663) (width 0.2))
        (gr_line (start -0.250195 1.279127) (end -1.083663 1.279127) (width 0.2))
      ))
    (pad "" smd custom (at 1.7 1.7 180) (size 0.62 0.62) (layers "F.Paste")
      (options (clearance outline) (anchor circle))
      (primitives
        (gr_arc (start -0.250195 1.279127) (mid 0.285453 0.294389) (end 1.266786 -0.24747) (width 0.2))
        (gr_arc (start -0.34334 1.279127) (mid 0.221018 0.229971) (end 1.266737 -0.340731) (width 0.2))
        (gr_arc (start -0.436309 1.279127) (mid 0.15516 0.166988) (end 1.262733 -0.432988) (width 0.2))
        (gr_arc (start -0.529126 1.279127) (mid 0.093127 0.100154) (end 1.269368 -0.527248) (width 0.2))
        (gr_arc (start -0.621807 1.279127) (mid 0.0309 0.033527) (end 1.275473 -0.621136) (width 0.2))
        (gr_arc (start -0.71437 1.279127) (mid -0.037758 -0.026651) (end 1.263665 -0.711602) (width 0.2))
        (gr_arc (start -0.806826 1.279127) (mid -0.105832 -0.087398) (end 1.253445 -0.802344) (width 0.2))
        (gr_arc (start -0.899187 1.279127) (mid -0.163611 -0.158516) (end 1.272017 -0.898016) (width 0.2))
        (gr_arc (start -0.991463 1.279127) (mid -0.228522 -0.222449) (end 1.270645 -0.990112) (width 0.2))
        (gr_arc (start -1.083663 1.279127) (mid -0.294507 -0.285313) (end 1.266278 -1.081674) (width 0.2))
        (gr_line (start 1.279127 -0.250195) (end 1.279127 -1.083663) (width 0.2))
        (gr_line (start -0.250195 1.279127) (end -1.083663 1.279127) (width 0.2))
      ))
    (pad "1" thru_hole circle (at 0 0) (size 6 6) (drill 3.7) (layers "*.Cu" "*.Mask")
      (net 220 "unconnected-(SP5-Pad1)") (pintype "passive+no_connect") (solder_paste_margin -1.2))
  )
	(footprint "scalenode-cm4-baseboard-footprints:Spacer_Drill3.7mm_H3mm_9774030151R" (layer "F.Cu")
    (at 145.488 93.2)
    (property "Author" "Antmicro")
    (property "License" "Apache-2.0")
    (property "MPN" "9774030151R")
    (property "Manufacturer" "Würth Elektronik")
    (property "Sheetfile" "compute-module.kicad_sch")
    (property "Sheetname" "Compute module")
    (property "ki_description" "Spacer, SMT,  Steel, Swage Round, 5.1mmx3mm, M3 Thread, WA-SMSI Series")
    (property "ki_keywords" "SPACER")
    (attr through_hole)
    (fp_text reference "SP4" (at -0.713 -3.65) (layer "F.SilkS")
        (effects (font (size 0.7 0.7) (thickness 0.15)) (justify left bottom))
    )
    (fp_text value "Spacer_Drill3.7mm_H3mm_9774030151R" (at 1.762 2.475) (layer "F.Fab")
        (effects (font (size 0.7 0.7) (thickness 0.15)) (justify left bottom))
    )
    (fp_text user "Author: Antmicro" (at -2.601 7.599) (layer "F.Fab") hide
        (effects (font (size 0.7 0.7) (thickness 0.15)) (justify left bottom))
    )
    (fp_text user "License: Apache-2.0" (at -2.601 8.8) (layer "F.Fab") hide
        (effects (font (size 0.7 0.7) (thickness 0.15)) (justify left bottom))
    )
    (fp_text user "${REFERENCE}" (at -2.601 6.398) (layer "F.Fab") hide
        (effects (font (size 0.7 0.7) (thickness 0.15)) (justify left bottom))
    )
    (fp_circle (center 0 0) (end 3.1 0)
      (stroke (width 0.12) (type solid)) (fill none) (layer "F.SilkS"))
    (fp_circle (center 0 0) (end 3.15 0)
      (stroke (width 0.05) (type solid)) (fill none) (layer "F.CrtYd"))
    (pad "" smd custom (at -1.709 -1.709) (size 0.62 0.62) (layers "F.Paste")
      (options (clearance outline) (anchor circle))
      (primitives
        (gr_arc (start -0.250195 1.279127) (mid 0.285453 0.294389) (end 1.266786 -0.24747) (width 0.2))
        (gr_arc (start -0.34334 1.279127) (mid 0.221018 0.229971) (end 1.266737 -0.340731) (width 0.2))
        (gr_arc (start -0.436309 1.279127) (mid 0.15516 0.166988) (end 1.262733 -0.432988) (width 0.2))
        (gr_arc (start -0.529126 1.279127) (mid 0.093127 0.100154) (end 1.269368 -0.527248) (width 0.2))
        (gr_arc (start -0.621807 1.279127) (mid 0.0309 0.033527) (end 1.275473 -0.621136) (width 0.2))
        (gr_arc (start -0.71437 1.279127) (mid -0.037758 -0.026651) (end 1.263665 -0.711602) (width 0.2))
        (gr_arc (start -0.806826 1.279127) (mid -0.105832 -0.087398) (end 1.253445 -0.802344) (width 0.2))
        (gr_arc (start -0.899187 1.279127) (mid -0.163611 -0.158516) (end 1.272017 -0.898016) (width 0.2))
        (gr_arc (start -0.991463 1.279127) (mid -0.228522 -0.222449) (end 1.270645 -0.990112) (width 0.2))
        (gr_arc (start -1.083663 1.279127) (mid -0.294507 -0.285313) (end 1.266278 -1.081674) (width 0.2))
        (gr_line (start 1.279127 -0.250195) (end 1.279127 -1.083663) (width 0.2))
        (gr_line (start -0.250195 1.279127) (end -1.083663 1.279127) (width 0.2))
      ))
    (pad "" smd custom (at -1.709 1.7 90) (size 0.62 0.62) (layers "F.Paste")
      (options (clearance outline) (anchor circle))
      (primitives
        (gr_arc (start -0.250195 1.279127) (mid 0.285453 0.294389) (end 1.266786 -0.24747) (width 0.2))
        (gr_arc (start -0.34334 1.279127) (mid 0.221018 0.229971) (end 1.266737 -0.340731) (width 0.2))
        (gr_arc (start -0.436309 1.279127) (mid 0.15516 0.166988) (end 1.262733 -0.432988) (width 0.2))
        (gr_arc (start -0.529126 1.279127) (mid 0.093127 0.100154) (end 1.269368 -0.527248) (width 0.2))
        (gr_arc (start -0.621807 1.279127) (mid 0.0309 0.033527) (end 1.275473 -0.621136) (width 0.2))
        (gr_arc (start -0.71437 1.279127) (mid -0.037758 -0.026651) (end 1.263665 -0.711602) (width 0.2))
        (gr_arc (start -0.806826 1.279127) (mid -0.105832 -0.087398) (end 1.253445 -0.802344) (width 0.2))
        (gr_arc (start -0.899187 1.279127) (mid -0.163611 -0.158516) (end 1.272017 -0.898016) (width 0.2))
        (gr_arc (start -0.991463 1.279127) (mid -0.228522 -0.222449) (end 1.270645 -0.990112) (width 0.2))
        (gr_arc (start -1.083663 1.279127) (mid -0.294507 -0.285313) (end 1.266278 -1.081674) (width 0.2))
        (gr_line (start 1.279127 -0.250195) (end 1.279127 -1.083663) (width 0.2))
        (gr_line (start -0.250195 1.279127) (end -1.083663 1.279127) (width 0.2))
      ))
    (pad "" smd custom (at 1.7 -1.709 270) (size 0.62 0.62) (layers "F.Paste")
      (options (clearance outline) (anchor circle))
      (primitives
        (gr_arc (start -0.250195 1.279127) (mid 0.285453 0.294389) (end 1.266786 -0.24747) (width 0.2))
        (gr_arc (start -0.34334 1.279127) (mid 0.221018 0.229971) (end 1.266737 -0.340731) (width 0.2))
        (gr_arc (start -0.436309 1.279127) (mid 0.15516 0.166988) (end 1.262733 -0.432988) (width 0.2))
        (gr_arc (start -0.529126 1.279127) (mid 0.093127 0.100154) (end 1.269368 -0.527248) (width 0.2))
        (gr_arc (start -0.621807 1.279127) (mid 0.0309 0.033527) (end 1.275473 -0.621136) (width 0.2))
        (gr_arc (start -0.71437 1.279127) (mid -0.037758 -0.026651) (end 1.263665 -0.711602) (width 0.2))
        (gr_arc (start -0.806826 1.279127) (mid -0.105832 -0.087398) (end 1.253445 -0.802344) (width 0.2))
        (gr_arc (start -0.899187 1.279127) (mid -0.163611 -0.158516) (end 1.272017 -0.898016) (width 0.2))
        (gr_arc (start -0.991463 1.279127) (mid -0.228522 -0.222449) (end 1.270645 -0.990112) (width 0.2))
        (gr_arc (start -1.083663 1.279127) (mid -0.294507 -0.285313) (end 1.266278 -1.081674) (width 0.2))
        (gr_line (start 1.279127 -0.250195) (end 1.279127 -1.083663) (width 0.2))
        (gr_line (start -0.250195 1.279127) (end -1.083663 1.279127) (width 0.2))
      ))
    (pad "" smd custom (at 1.7 1.7 180) (size 0.62 0.62) (layers "F.Paste")
      (options (clearance outline) (anchor circle))
      (primitives
        (gr_arc (start -0.250195 1.279127) (mid 0.285453 0.294389) (end 1.266786 -0.24747) (width 0.2))
        (gr_arc (start -0.34334 1.279127) (mid 0.221018 0.229971) (end 1.266737 -0.340731) (width 0.2))
        (gr_arc (start -0.436309 1.279127) (mid 0.15516 0.166988) (end 1.262733 -0.432988) (width 0.2))
        (gr_arc (start -0.529126 1.279127) (mid 0.093127 0.100154) (end 1.269368 -0.527248) (width 0.2))
        (gr_arc (start -0.621807 1.279127) (mid 0.0309 0.033527) (end 1.275473 -0.621136) (width 0.2))
        (gr_arc (start -0.71437 1.279127) (mid -0.037758 -0.026651) (end 1.263665 -0.711602) (width 0.2))
        (gr_arc (start -0.806826 1.279127) (mid -0.105832 -0.087398) (end 1.253445 -0.802344) (width 0.2))
        (gr_arc (start -0.899187 1.279127) (mid -0.163611 -0.158516) (end 1.272017 -0.898016) (width 0.2))
        (gr_arc (start -0.991463 1.279127) (mid -0.228522 -0.222449) (end 1.270645 -0.990112) (width 0.2))
        (gr_arc (start -1.083663 1.279127) (mid -0.294507 -0.285313) (end 1.266278 -1.081674) (width 0.2))
        (gr_line (start 1.279127 -0.250195) (end 1.279127 -1.083663) (width 0.2))
        (gr_line (start -0.250195 1.279127) (end -1.083663 1.279127) (width 0.2))
      ))
    (pad "1" thru_hole circle (at 0 0) (size 6 6) (drill 3.7) (layers "*.Cu" "*.Mask")
      (net 219 "unconnected-(SP4-Pad1)") (pintype "passive+no_connect") (solder_paste_margin -1.2))
  )
)
